(kicad_pcb
	(version 20260206)
	(generator "pcbnew")
	(generator_version "10.0")
	(general
		(thickness 1.6)
		(legacy_teardrops no)
	)
	(paper "A4")
	(title_block
		(title "Wiwynn_Tioga_Pass_MB.brd")
		(comment 1 "Tioga Pass / footprints 2198-2204 of 4770")
	)
	(layers
		(0 "F.Cu" signal "TOP")
		(4 "In1.Cu" signal "L2GND")
		(6 "In2.Cu" signal "L3")
		(8 "In3.Cu" signal "L4GND")
		(10 "In4.Cu" signal "L5")
		(12 "In5.Cu" signal "L6GND")
		(14 "In6.Cu" signal "L7VCC")
		(16 "In7.Cu" signal "L8VCC")
		(18 "In8.Cu" signal "L9GND")
		(20 "In9.Cu" signal "L10")
		(22 "In10.Cu" signal "L11GND")
		(24 "In11.Cu" signal "L12")
		(26 "In12.Cu" signal "L13GND")
		(2 "B.Cu" signal "BOTTOM")
		(9 "F.Adhes" user "F.Adhesive")
		(11 "B.Adhes" user "B.Adhesive")
		(13 "F.Paste" user "Package Geometry/Pastemask Top")
		(15 "B.Paste" user "Package Geometry/Pastemask Bottom")
		(5 "F.SilkS" user "Ref Des/Silkscreen Top")
		(7 "B.SilkS" user "Ref Des/Silkscreen Bottom")
		(1 "F.Mask" user "Board Geometry/Soldermask Top")
		(3 "B.Mask" user "Board Geometry/Soldermask Bottom")
		(17 "Dwgs.User" user "User.Drawings")
		(19 "Cmts.User" user "User.Comments")
		(21 "Eco1.User" user "User.Eco1")
		(23 "Eco2.User" user "User.Eco2")
		(25 "Edge.Cuts" user "Board Geometry/Outline")
		(27 "Margin" user)
		(31 "F.CrtYd" user "Package Geometry/Place Bound Top")
		(29 "B.CrtYd" user "Package Geometry/Place Bound Bottom")
		(35 "F.Fab" user "Ref Des/Assembly Top")
		(33 "B.Fab" user "Ref Des/Assembly Bottom")
	)
	(footprint ""
		(layer "F.Cu")
		(at 386.2705 -79.8322 90)
		(property "Reference" "R7D26"
			(at 0 0 90)
			(layer "F.SilkS")
			(hide yes)
			(effects
				(font
					(size 1.27 1.27)
				)
			)
		)
		(property "Value" ""
			(at 0 0 90)
			(layer "F.Fab")
			(effects
				(font
					(size 1.27 1.27)
				)
			)
		)
		(duplicate_pad_numbers_are_jumpers no)
		(fp_poly
			(pts
				(xy -0.2794 -0.1016) (xy 0.2794 -0.1016) (xy 0.2794 0.9906) (xy -0.2794 0.9906)
			)
			(stroke
				(width 0)
				(type default)
			)
			(fill no)
			(layer "F.CrtYd")
		)
		(fp_line
			(start 0.2794 -0.1016)
			(end -0.2794 -0.1016)
			(stroke
				(width 0.1)
				(type default)
			)
			(layer "F.Fab")
		)
		(fp_line
			(start -0.2794 -0.1016)
			(end -0.2794 0.9906)
			(stroke
				(width 0.1)
				(type default)
			)
			(layer "F.Fab")
		)
		(fp_line
			(start 0.2794 0.9906)
			(end 0.2794 -0.1016)
			(stroke
				(width 0.1)
				(type default)
			)
			(layer "F.Fab")
		)
		(fp_line
			(start -0.2794 0.9906)
			(end 0.2794 0.9906)
			(stroke
				(width 0.1)
				(type default)
			)
			(layer "F.Fab")
		)
		(pad "1" smd rect
			(at 0 0 90)
			(size 0.508 0.508)
			(layers "F.Cu" "F.Mask" "F.Paste")
			(net "PD_GTL2104_DIR_0")
		)
		(pad "2" smd rect
			(at 0 0.889 90)
			(size 0.508 0.508)
			(layers "F.Cu" "F.Mask" "F.Paste")
			(net "GND")
		)
		(zone
			(layer "F.Cu")
			(hatch none 0.5)
			(connect_pads
				(clearance 0)
			)
			(min_thickness 0.25)
			(keepout
				(tracks allowed)
				(vias not_allowed)
				(pads allowed)
				(copperpour not_allowed)
				(footprints allowed)
			)
			(placement
				(enabled no)
				(sheetname "")
			)
			(fill
				(thermal_gap 0.5)
				(thermal_bridge_width 0.5)
				(island_removal_mode 0)
			)
			(polygon
				(pts
					(xy 386.5245 -79.5782) (xy 386.5245 -80.0862) (xy 386.9055 -80.0862) (xy 386.9055 -79.5782)
				)
			)
		)
		(zone
			(layer "F.Cu")
			(hatch none 0.5)
			(connect_pads
				(clearance 0)
			)
			(min_thickness 0.25)
			(keepout
				(tracks not_allowed)
				(vias allowed)
				(pads allowed)
				(copperpour not_allowed)
				(footprints allowed)
			)
			(placement
				(enabled no)
				(sheetname "")
			)
			(fill
				(thermal_gap 0.5)
				(thermal_bridge_width 0.5)
				(island_removal_mode 0)
			)
			(polygon
				(pts
					(xy 386.9055 -79.5782) (xy 386.9055 -80.0862) (xy 386.5245 -80.0862) (xy 386.5245 -79.5782)
				)
			)
		)
	)
	(footprint ""
		(layer "F.Cu")
		(at 168.7322 -8.0137)
		(property "Reference" "R4G10"
			(at 0 0 0)
			(layer "F.SilkS")
			(hide yes)
			(effects
				(font
					(size 1.27 1.27)
				)
			)
		)
		(property "Value" ""
			(at 0 0 0)
			(layer "F.Fab")
			(effects
				(font
					(size 1.27 1.27)
				)
			)
		)
		(duplicate_pad_numbers_are_jumpers no)
		(fp_poly
			(pts
				(xy -0.2794 -0.1016) (xy 0.2794 -0.1016) (xy 0.2794 0.9906) (xy -0.2794 0.9906)
			)
			(stroke
				(width 0)
				(type default)
			)
			(fill no)
			(layer "F.CrtYd")
		)
		(fp_line
			(start -0.2794 -0.1016)
			(end -0.2794 0.9906)
			(stroke
				(width 0.1)
				(type default)
			)
			(layer "F.Fab")
		)
		(fp_line
			(start -0.2794 0.9906)
			(end 0.2794 0.9906)
			(stroke
				(width 0.1)
				(type default)
			)
			(layer "F.Fab")
		)
		(fp_line
			(start 0.2794 -0.1016)
			(end -0.2794 -0.1016)
			(stroke
				(width 0.1)
				(type default)
			)
			(layer "F.Fab")
		)
		(fp_line
			(start 0.2794 0.9906)
			(end 0.2794 -0.1016)
			(stroke
				(width 0.1)
				(type default)
			)
			(layer "F.Fab")
		)
		(pad "1" smd rect
			(at 0 0)
			(size 0.508 0.508)
			(layers "F.Cu" "F.Mask" "F.Paste")
			(net "VSENSE_PVPP_GHJ")
		)
		(pad "2" smd rect
			(at 0 0.889)
			(size 0.508 0.508)
			(layers "F.Cu" "F.Mask" "F.Paste")
			(net "VR_COMP_PVPP_GHJ")
		)
		(zone
			(layer "F.Cu")
			(hatch none 0.5)
			(connect_pads
				(clearance 0)
			)
			(min_thickness 0.25)
			(keepout
				(tracks allowed)
				(vias not_allowed)
				(pads allowed)
				(copperpour not_allowed)
				(footprints allowed)
			)
			(placement
				(enabled no)
				(sheetname "")
			)
			(fill
				(thermal_gap 0.5)
				(thermal_bridge_width 0.5)
				(island_removal_mode 0)
			)
			(polygon
				(pts
					(xy 168.4782 -7.7597) (xy 168.9862 -7.7597) (xy 168.9862 -7.3787) (xy 168.4782 -7.3787)
				)
			)
		)
		(zone
			(layer "F.Cu")
			(hatch none 0.5)
			(connect_pads
				(clearance 0)
			)
			(min_thickness 0.25)
			(keepout
				(tracks not_allowed)
				(vias allowed)
				(pads allowed)
				(copperpour not_allowed)
				(footprints allowed)
			)
			(placement
				(enabled no)
				(sheetname "")
			)
			(fill
				(thermal_gap 0.5)
				(thermal_bridge_width 0.5)
				(island_removal_mode 0)
			)
			(polygon
				(pts
					(xy 168.4782 -7.3787) (xy 168.9862 -7.3787) (xy 168.9862 -7.7597) (xy 168.4782 -7.7597)
				)
			)
		)
	)
	(footprint ""
		(layer "F.Cu")
		(at 401.7518 -53.53558 -90)
		(property "Reference" "R7F5"
			(at 0 0 270)
			(layer "F.SilkS")
			(hide yes)
			(effects
				(font
					(size 1.27 1.27)
				)
			)
		)
		(property "Value" ""
			(at 0 0 270)
			(layer "F.Fab")
			(effects
				(font
					(size 1.27 1.27)
				)
			)
		)
		(duplicate_pad_numbers_are_jumpers no)
		(fp_poly
			(pts
				(xy -0.2794 -0.1016) (xy 0.2794 -0.1016) (xy 0.2794 0.9906) (xy -0.2794 0.9906)
			)
			(stroke
				(width 0)
				(type default)
			)
			(fill no)
			(layer "F.CrtYd")
		)
		(fp_line
			(start -0.2794 0.9906)
			(end 0.2794 0.9906)
			(stroke
				(width 0.1)
				(type default)
			)
			(layer "F.Fab")
		)
		(fp_line
			(start 0.2794 0.9906)
			(end 0.2794 -0.1016)
			(stroke
				(width 0.1)
				(type default)
			)
			(layer "F.Fab")
		)
		(fp_line
			(start -0.2794 -0.1016)
			(end -0.2794 0.9906)
			(stroke
				(width 0.1)
				(type default)
			)
			(layer "F.Fab")
		)
		(fp_line
			(start 0.2794 -0.1016)
			(end -0.2794 -0.1016)
			(stroke
				(width 0.1)
				(type default)
			)
			(layer "F.Fab")
		)
		(pad "1" smd rect
			(at 0 0 270)
			(size 0.508 0.508)
			(layers "F.Cu" "F.Mask" "F.Paste")
			(net "P3V3_STBY")
		)
		(pad "2" smd rect
			(at 0 0.889 270)
			(size 0.508 0.508)
			(layers "F.Cu" "F.Mask" "F.Paste")
			(net "SPI_CS0_PRIMARY_R_N")
		)
		(zone
			(layer "F.Cu")
			(hatch none 0.5)
			(connect_pads
				(clearance 0)
			)
			(min_thickness 0.25)
			(keepout
				(tracks not_allowed)
				(vias allowed)
				(pads allowed)
				(copperpour not_allowed)
				(footprints allowed)
			)
			(placement
				(enabled no)
				(sheetname "")
			)
			(fill
				(thermal_gap 0.5)
				(thermal_bridge_width 0.5)
				(island_removal_mode 0)
			)
			(polygon
				(pts
					(xy 401.1168 -53.78958) (xy 401.1168 -53.28158) (xy 401.4978 -53.28158) (xy 401.4978 -53.78958)
				)
			)
		)
		(zone
			(layer "F.Cu")
			(hatch none 0.5)
			(connect_pads
				(clearance 0)
			)
			(min_thickness 0.25)
			(keepout
				(tracks allowed)
				(vias not_allowed)
				(pads allowed)
				(copperpour not_allowed)
				(footprints allowed)
			)
			(placement
				(enabled no)
				(sheetname "")
			)
			(fill
				(thermal_gap 0.5)
				(thermal_bridge_width 0.5)
				(island_removal_mode 0)
			)
			(polygon
				(pts
					(xy 401.4978 -53.78958) (xy 401.4978 -53.28158) (xy 401.1168 -53.28158) (xy 401.1168 -53.78958)
				)
			)
		)
	)
	(footprint ""
		(layer "F.Cu")
		(at 198.00443 -69.318124 90)
		(property "Reference" "C4D13"
			(at -0.8382 -0.67818 90)
			(unlocked yes)
			(layer "F.SilkS")
			(effects
				(font
					(size 0.4064 0.254)
					(thickness 0.1524)
				)
				(justify left)
			)
		)
		(property "Value" ""
			(at 0 0 90)
			(layer "F.Fab")
			(effects
				(font
					(size 1.27 1.27)
				)
			)
		)
		(duplicate_pad_numbers_are_jumpers no)
		(fp_poly
			(pts
				(xy 0.3048 -0.1016) (xy 0.3048 0.9906) (xy -0.3048 0.9906) (xy -0.3048 -0.1016)
			)
			(stroke
				(width 0)
				(type default)
			)
			(fill no)
			(layer "F.CrtYd")
		)
		(fp_line
			(start 0.3048 -0.1016)
			(end -0.3048 -0.1016)
			(stroke
				(width 0.1)
				(type default)
			)
			(layer "F.Fab")
		)
		(fp_line
			(start -0.3048 -0.1016)
			(end -0.3048 0.9906)
			(stroke
				(width 0.1)
				(type default)
			)
			(layer "F.Fab")
		)
		(fp_line
			(start 0.3048 0.9906)
			(end 0.3048 -0.1016)
			(stroke
				(width 0.1)
				(type default)
			)
			(layer "F.Fab")
		)
		(fp_line
			(start -0.3048 0.9906)
			(end 0.3048 0.9906)
			(stroke
				(width 0.1)
				(type default)
			)
			(layer "F.Fab")
		)
		(pad "1" smd rect
			(at 0 0 90)
			(size 0.508 0.508)
			(layers "F.Cu" "F.Mask" "F.Paste")
			(net "P5V_STBY")
		)
		(pad "2" smd rect
			(at 0 0.889 90)
			(size 0.508 0.508)
			(layers "F.Cu" "F.Mask" "F.Paste")
			(net "GND")
		)
		(zone
			(layer "F.Cu")
			(hatch none 0.5)
			(connect_pads
				(clearance 0)
			)
			(min_thickness 0.25)
			(keepout
				(tracks allowed)
				(vias not_allowed)
				(pads allowed)
				(copperpour not_allowed)
				(footprints allowed)
			)
			(placement
				(enabled no)
				(sheetname "")
			)
			(fill
				(thermal_gap 0.5)
				(thermal_bridge_width 0.5)
				(island_removal_mode 0)
			)
			(polygon
				(pts
					(xy 198.25843 -69.064124) (xy 198.25843 -69.572124) (xy 198.63943 -69.572124) (xy 198.63943 -69.064124)
				)
			)
		)
		(zone
			(layer "F.Cu")
			(hatch none 0.5)
			(connect_pads
				(clearance 0)
			)
			(min_thickness 0.25)
			(keepout
				(tracks not_allowed)
				(vias allowed)
				(pads allowed)
				(copperpour not_allowed)
				(footprints allowed)
			)
			(placement
				(enabled no)
				(sheetname "")
			)
			(fill
				(thermal_gap 0.5)
				(thermal_bridge_width 0.5)
				(island_removal_mode 0)
			)
			(polygon
				(pts
					(xy 198.63943 -69.064124) (xy 198.63943 -69.572124) (xy 198.25843 -69.572124) (xy 198.25843 -69.064124)
				)
			)
		)
	)
	(footprint ""
		(layer "F.Cu")
		(at 163.88842 -124.5235)
		(property "Reference" "Q4B2"
			(at 1.33858 -1.05283 0)
			(unlocked yes)
			(layer "F.SilkS")
			(effects
				(font
					(size 0.7874 0.5842)
					(thickness 0.1524)
				)
				(justify left)
			)
		)
		(property "Value" ""
			(at 0 0 0)
			(layer "F.Fab")
			(effects
				(font
					(size 1.27 1.27)
				)
			)
		)
		(duplicate_pad_numbers_are_jumpers no)
		(fp_circle
			(center -0.508 -0.7874)
			(end -0.381 -0.7874)
			(stroke
				(width 0.254)
				(type default)
			)
			(fill no)
			(layer "F.SilkS")
		)
		(fp_poly
			(pts
				(xy 0.2159 1.7526) (xy 1.5621 1.7526) (xy 1.5621 -0.4572) (xy 0.2159 -0.4572)
			)
			(stroke
				(width 0)
				(type default)
			)
			(fill no)
			(layer "F.CrtYd")
		)
		(fp_line
			(start 0.2159 -0.45466)
			(end 0.2159 1.75514)
			(stroke
				(width 0.1)
				(type default)
			)
			(layer "F.Fab")
		)
		(fp_line
			(start 0.2159 1.75514)
			(end 1.5621 1.75514)
			(stroke
				(width 0.1)
				(type default)
			)
			(layer "F.Fab")
		)
		(fp_line
			(start 1.5621 -0.45466)
			(end 0.2159 -0.45466)
			(stroke
				(width 0.1)
				(type default)
			)
			(layer "F.Fab")
		)
		(fp_line
			(start 1.5621 1.75514)
			(end 1.5621 -0.45466)
			(stroke
				(width 0.1)
				(type default)
			)
			(layer "F.Fab")
		)
		(fp_circle
			(center -0.508 -0.7874)
			(end -0.381 -0.7874)
			(stroke
				(width 0.254)
				(type default)
			)
			(fill no)
			(layer "F.Fab")
		)
		(pad "1" smd rect
			(at 0 0)
			(size 1.016 0.381)
			(layers "F.Cu" "F.Mask" "F.Paste")
			(net "GND")
		)
		(pad "2" smd rect
			(at 0 0.65024)
			(size 1.016 0.381)
			(layers "F.Cu" "F.Mask" "F.Paste")
			(net "FM_SYS_THROTTLE_LVC3")
		)
		(pad "3" smd rect
			(at 0 1.30048)
			(size 1.016 0.381)
			(layers "F.Cu" "F.Mask" "F.Paste")
			(net "H_CPU1_MEMKLM_MEMHOT_G_N")
		)
		(pad "4" smd rect
			(at 1.778 1.30048)
			(size 1.016 0.381)
			(layers "F.Cu" "F.Mask" "F.Paste")
			(net "GND")
		)
		(pad "5" smd rect
			(at 1.778 0.65024)
			(size 1.016 0.381)
			(layers "F.Cu" "F.Mask" "F.Paste")
			(net "FM_SYS_THROTTLE_LVC3")
		)
		(pad "6" smd rect
			(at 1.778 0)
			(size 1.016 0.381)
			(layers "F.Cu" "F.Mask" "F.Paste")
			(net "H_CPU1_MEMGHJ_MEMHOT_G_N")
		)
		(zone
			(layer "F.Cu")
			(hatch none 0.5)
			(connect_pads
				(clearance 0)
			)
			(min_thickness 0.25)
			(keepout
				(tracks allowed)
				(vias not_allowed)
				(pads allowed)
				(copperpour not_allowed)
				(footprints allowed)
			)
			(placement
				(enabled no)
				(sheetname "")
			)
			(fill
				(thermal_gap 0.5)
				(thermal_bridge_width 0.5)
				(island_removal_mode 0)
			)
			(polygon
				(pts
					(xy 163.38042 -124.714) (xy 164.39642 -124.714) (xy 164.39642 -123.0249) (xy 163.38042 -123.0249)
				)
			)
		)
		(zone
			(layer "F.Cu")
			(hatch none 0.5)
			(connect_pads
				(clearance 0)
			)
			(min_thickness 0.25)
			(keepout
				(tracks allowed)
				(vias not_allowed)
				(pads allowed)
				(copperpour not_allowed)
				(footprints allowed)
			)
			(placement
				(enabled no)
				(sheetname "")
			)
			(fill
				(thermal_gap 0.5)
				(thermal_bridge_width 0.5)
				(island_removal_mode 0)
			)
			(polygon
				(pts
					(xy 165.15842 -124.714) (xy 166.17442 -124.714) (xy 166.17442 -123.0249) (xy 165.15842 -123.0249)
				)
			)
		)
	)
	(footprint ""
		(layer "F.Cu")
		(at 170.7896 -131.0005 180)
		(property "Reference" "R4B5"
			(at 0 0 180)
			(layer "F.SilkS")
			(hide yes)
			(effects
				(font
					(size 1.27 1.27)
				)
			)
		)
		(property "Value" ""
			(at 0 0 180)
			(layer "F.Fab")
			(effects
				(font
					(size 1.27 1.27)
				)
			)
		)
		(duplicate_pad_numbers_are_jumpers no)
		(fp_poly
			(pts
				(xy -0.2794 -0.1016) (xy 0.2794 -0.1016) (xy 0.2794 0.9906) (xy -0.2794 0.9906)
			)
			(stroke
				(width 0)
				(type default)
			)
			(fill no)
			(layer "F.CrtYd")
		)
		(fp_line
			(start 0.2794 0.9906)
			(end 0.2794 -0.1016)
			(stroke
				(width 0.1)
				(type default)
			)
			(layer "F.Fab")
		)
		(fp_line
			(start 0.2794 -0.1016)
			(end -0.2794 -0.1016)
			(stroke
				(width 0.1)
				(type default)
			)
			(layer "F.Fab")
		)
		(fp_line
			(start -0.2794 0.9906)
			(end 0.2794 0.9906)
			(stroke
				(width 0.1)
				(type default)
			)
			(layer "F.Fab")
		)
		(fp_line
			(start -0.2794 -0.1016)
			(end -0.2794 0.9906)
			(stroke
				(width 0.1)
				(type default)
			)
			(layer "F.Fab")
		)
		(pad "1" smd rect
			(at 0 0 180)
			(size 0.508 0.508)
			(layers "F.Cu" "F.Mask" "F.Paste")
			(net "VSENSE_PVPP_KLM")
		)
		(pad "2" smd rect
			(at 0 0.889 180)
			(size 0.508 0.508)
			(layers "F.Cu" "F.Mask" "F.Paste")
			(net "VR_FB_PVPP_KLM")
		)
		(zone
			(layer "F.Cu")
			(hatch none 0.5)
			(connect_pads
				(clearance 0)
			)
			(min_thickness 0.25)
			(keepout
				(tracks not_allowed)
				(vias allowed)
				(pads allowed)
				(copperpour not_allowed)
				(footprints allowed)
			)
			(placement
				(enabled no)
				(sheetname "")
			)
			(fill
				(thermal_gap 0.5)
				(thermal_bridge_width 0.5)
				(island_removal_mode 0)
			)
			(polygon
				(pts
					(xy 171.0436 -131.6355) (xy 170.5356 -131.6355) (xy 170.5356 -131.2545) (xy 171.0436 -131.2545)
				)
			)
		)
		(zone
			(layer "F.Cu")
			(hatch none 0.5)
			(connect_pads
				(clearance 0)
			)
			(min_thickness 0.25)
			(keepout
				(tracks allowed)
				(vias not_allowed)
				(pads allowed)
				(copperpour not_allowed)
				(footprints allowed)
			)
			(placement
				(enabled no)
				(sheetname "")
			)
			(fill
				(thermal_gap 0.5)
				(thermal_bridge_width 0.5)
				(island_removal_mode 0)
			)
			(polygon
				(pts
					(xy 171.0436 -131.2545) (xy 170.5356 -131.2545) (xy 170.5356 -131.6355) (xy 171.0436 -131.6355)
				)
			)
		)
	)
	(footprint ""
		(layer "F.Cu")
		(at 174.3583 -150.114 90)
		(property "Reference" "R4A4"
			(at 0 0 90)
			(layer "F.SilkS")
			(hide yes)
			(effects
				(font
					(size 1.27 1.27)
				)
			)
		)
		(property "Value" ""
			(at 0 0 90)
			(layer "F.Fab")
			(effects
				(font
					(size 1.27 1.27)
				)
			)
		)
		(duplicate_pad_numbers_are_jumpers no)
		(fp_poly
			(pts
				(xy -0.2794 -0.1016) (xy 0.2794 -0.1016) (xy 0.2794 0.9906) (xy -0.2794 0.9906)
			)
			(stroke
				(width 0)
				(type default)
			)
			(fill no)
			(layer "F.CrtYd")
		)
		(fp_line
			(start 0.2794 -0.1016)
			(end -0.2794 -0.1016)
			(stroke
				(width 0.1)
				(type default)
			)
			(layer "F.Fab")
		)
		(fp_line
			(start -0.2794 -0.1016)
			(end -0.2794 0.9906)
			(stroke
				(width 0.1)
				(type default)
			)
			(layer "F.Fab")
		)
		(fp_line
			(start 0.2794 0.9906)
			(end 0.2794 -0.1016)
			(stroke
				(width 0.1)
				(type default)
			)
			(layer "F.Fab")
		)
		(fp_line
			(start -0.2794 0.9906)
			(end 0.2794 0.9906)
			(stroke
				(width 0.1)
				(type default)
			)
			(layer "F.Fab")
		)
		(pad "1" smd rect
			(at 0 0 90)
			(size 0.508 0.508)
			(layers "F.Cu" "F.Mask" "F.Paste")
			(net "PWRGD_PVTT_KLM_CPU1_R")
		)
		(pad "2" smd rect
			(at 0 0.889 90)
			(size 0.508 0.508)
			(layers "F.Cu" "F.Mask" "F.Paste")
			(net "PWRGD_PVTT_CPU1")
		)
		(zone
			(layer "F.Cu")
			(hatch none 0.5)
			(connect_pads
				(clearance 0)
			)
			(min_thickness 0.25)
			(keepout
				(tracks allowed)
				(vias not_allowed)
				(pads allowed)
				(copperpour not_allowed)
				(footprints allowed)
			)
			(placement
				(enabled no)
				(sheetname "")
			)
			(fill
				(thermal_gap 0.5)
				(thermal_bridge_width 0.5)
				(island_removal_mode 0)
			)
			(polygon
				(pts
					(xy 174.6123 -149.86) (xy 174.6123 -150.368) (xy 174.9933 -150.368) (xy 174.9933 -149.86)
				)
			)
		)
		(zone
			(layer "F.Cu")
			(hatch none 0.5)
			(connect_pads
				(clearance 0)
			)
			(min_thickness 0.25)
			(keepout
				(tracks not_allowed)
				(vias allowed)
				(pads allowed)
				(copperpour not_allowed)
				(footprints allowed)
			)
			(placement
				(enabled no)
				(sheetname "")
			)
			(fill
				(thermal_gap 0.5)
				(thermal_bridge_width 0.5)
				(island_removal_mode 0)
			)
			(polygon
				(pts
					(xy 174.9933 -149.86) (xy 174.9933 -150.368) (xy 174.6123 -150.368) (xy 174.6123 -149.86)
				)
			)
		)
	)
)
